# S9S_MB_2U (Grand Teton) — schematic netlist excerpt (pin names and nets, part order shuffled) for the footprints in the layout excerpt that follows; sources: Cadence DE-HDL packaged netlist, KiCad conversion of 03242023_DA0F0TMBIJ0_F0T_Motherboard_J_brd_V01_OCP.brd

C937  Q_CAP_DIFFBUS  DIFF BUS_0.22UF 6.3V 20% X6S  pkg C0201  page 173 : \1\ = P5E_CPU0_PE2_TX_C_DP<14> ; \2\ = P5E_CPU0_PE2_TX_DP<14>
R4578  Q_RES  0 5% EMPTY  pkg 0402LF  page 146 : A = PRSNT_CABLE_GPU_A2_N ; B = PRSNT_CABLE_GPU_A2_ISO_N
R4610  Q_RES  33.2 1% CHIP  pkg 0402LF  page 214 : A = CLK_GEN2_GPU_FPGA_OE_R_N ; B = CLK_GEN2_GPU_FPGA_OE_N

(kicad_pcb
	(version 20260206)
	(generator "pcbnew")
	(generator_version "10.0")
	(general
		(thickness 1.6)
		(legacy_teardrops no)
	)
	(paper "A4")
	(title_block
		(title "03242023_DA0F0TMBIJ0_F0T_Motherboard_J_brd_V01_OCP.brd")
		(comment 1 "Grand Teton / footprints 3971-3973 of 6105")
	)
	(layers
		(0 "F.Cu" signal "TOP")
		(4 "In1.Cu" signal "GND")
		(6 "In2.Cu" signal "IN1")
		(8 "In3.Cu" signal "GND1")
		(10 "In4.Cu" signal "IN2")
		(12 "In5.Cu" signal "GND2")
		(14 "In6.Cu" signal "IN3")
		(16 "In7.Cu" signal "GND3")
		(18 "In8.Cu" signal "VCC")
		(20 "In9.Cu" signal "VCC1")
		(22 "In10.Cu" signal "GND4")
		(24 "In11.Cu" signal "IN4")
		(26 "In12.Cu" signal "GND5")
		(28 "In13.Cu" signal "IN5")
		(30 "In14.Cu" signal "GND6")
		(32 "In15.Cu" signal "IN6")
		(34 "In16.Cu" signal "GND7")
		(2 "B.Cu" signal "BOTTOM")
		(9 "F.Adhes" user "F.Adhesive")
		(11 "B.Adhes" user "B.Adhesive")
		(13 "F.Paste" user "Package Geometry/Pastemask Top")
		(15 "B.Paste" user "Package Geometry/Pastemask Bottom")
		(5 "F.SilkS" user "Ref Des/Silkscreen Top")
		(7 "B.SilkS" user "Ref Des/Silkscreen Bottom")
		(1 "F.Mask" user "Board Geometry/Soldermask Top")
		(3 "B.Mask" user "Board Geometry/Soldermask Bottom")
		(17 "Dwgs.User" user "User.Drawings")
		(19 "Cmts.User" user "User.Comments")
		(21 "Eco1.User" user "User.Eco1")
		(23 "Eco2.User" user "User.Eco2")
		(25 "Edge.Cuts" user "Board Geometry/Outline")
		(27 "Margin" user)
		(31 "F.CrtYd" user "Package Geometry/Place Bound Top")
		(29 "B.CrtYd" user "Package Geometry/Place Bound Bottom")
		(35 "F.Fab" user "Ref Des/Assembly Top")
		(33 "B.Fab" user "Ref Des/Assembly Bottom")
	)
	(footprint ""
		(layer "F.Cu")
		(at 306.22367 -428.86249)
		(property "Reference" "R4578"
			(at 0 0 0)
			(layer "F.SilkS")
			(hide yes)
			(effects
				(font
					(size 1.27 1.27)
				)
			)
		)
		(property "Value" ""
			(at 0 0 0)
			(layer "F.Fab")
			(effects
				(font
					(size 1.27 1.27)
				)
			)
		)
		(duplicate_pad_numbers_are_jumpers no)
		(fp_line
			(start -0.7874 -0.4064)
			(end 0.7874 -0.4064)
			(stroke
				(width 0.1524)
				(type default)
			)
			(layer "F.SilkS")
		)
		(fp_line
			(start -0.7874 0.4064)
			(end -0.7874 -0.4064)
			(stroke
				(width 0.1524)
				(type default)
			)
			(layer "F.SilkS")
		)
		(fp_line
			(start 0.7874 -0.4064)
			(end 0.7874 0.4064)
			(stroke
				(width 0.1524)
				(type default)
			)
			(layer "F.SilkS")
		)
		(fp_line
			(start 0.7874 0.4064)
			(end -0.7874 0.4064)
			(stroke
				(width 0.1524)
				(type default)
			)
			(layer "F.SilkS")
		)
		(fp_line
			(start -0.67945 -0.305054)
			(end -0.12065 -0.305054)
			(stroke
				(width 0.1)
				(type default)
			)
			(layer "F.Fab")
		)
		(fp_line
			(start -0.67945 0.3048)
			(end -0.67945 -0.305054)
			(stroke
				(width 0.1)
				(type default)
			)
			(layer "F.Fab")
		)
		(fp_line
			(start -0.12065 -0.305054)
			(end -0.12065 -0.2794)
			(stroke
				(width 0.1)
				(type default)
			)
			(layer "F.Fab")
		)
		(fp_line
			(start -0.12065 -0.2794)
			(end 0.12065 -0.2794)
			(stroke
				(width 0.1)
				(type default)
			)
			(layer "F.Fab")
		)
		(fp_line
			(start -0.12065 0.2794)
			(end -0.12065 0.3048)
			(stroke
				(width 0.1)
				(type default)
			)
			(layer "F.Fab")
		)
		(fp_line
			(start -0.12065 0.3048)
			(end -0.67945 0.3048)
			(stroke
				(width 0.1)
				(type default)
			)
			(layer "F.Fab")
		)
		(fp_line
			(start 0.120396 0.2794)
			(end -0.12065 0.2794)
			(stroke
				(width 0.1)
				(type default)
			)
			(layer "F.Fab")
		)
		(fp_line
			(start 0.120396 0.3048)
			(end 0.120396 0.2794)
			(stroke
				(width 0.1)
				(type default)
			)
			(layer "F.Fab")
		)
		(fp_line
			(start 0.12065 -0.3048)
			(end 0.67945 -0.3048)
			(stroke
				(width 0.1)
				(type default)
			)
			(layer "F.Fab")
		)
		(fp_line
			(start 0.12065 -0.2794)
			(end 0.12065 -0.3048)
			(stroke
				(width 0.1)
				(type default)
			)
			(layer "F.Fab")
		)
		(fp_line
			(start 0.67945 -0.3048)
			(end 0.67945 0.3048)
			(stroke
				(width 0.1)
				(type default)
			)
			(layer "F.Fab")
		)
		(fp_line
			(start 0.67945 0.3048)
			(end 0.120396 0.3048)
			(stroke
				(width 0.1)
				(type default)
			)
			(layer "F.Fab")
		)
		(pad "1" smd circle
			(at -0.40005 0)
			(size 0 0)
			(layers "F.Cu" "F.Mask" "F.Paste")
			(net "PRSNT_CABLE_GPU_A2_N")
		)
		(pad "2" smd circle
			(at 0.40005 0)
			(size 0 0)
			(layers "F.Cu" "F.Mask" "F.Paste")
			(net "PRSNT_CABLE_GPU_A2_ISO_N")
		)
	)
	(footprint ""
		(layer "F.Cu")
		(at 374.46077 -402.371052 -90)
		(property "Reference" "C937"
			(at 0 0 270)
			(layer "F.SilkS")
			(hide yes)
			(effects
				(font
					(size 1.27 1.27)
				)
			)
		)
		(property "Value" ""
			(at 0 0 270)
			(layer "F.Fab")
			(effects
				(font
					(size 1.27 1.27)
				)
			)
		)
		(duplicate_pad_numbers_are_jumpers no)
		(fp_line
			(start -0.299974 0.150114)
			(end -0.299974 -0.150114)
			(stroke
				(width 0.1)
				(type default)
			)
			(layer "F.Fab")
		)
		(fp_line
			(start 0.299974 0.150114)
			(end -0.299974 0.150114)
			(stroke
				(width 0.1)
				(type default)
			)
			(layer "F.Fab")
		)
		(fp_line
			(start -0.299974 -0.150114)
			(end 0.299974 -0.150114)
			(stroke
				(width 0.1)
				(type default)
			)
			(layer "F.Fab")
		)
		(fp_line
			(start 0.299974 -0.150114)
			(end 0.299974 0.150114)
			(stroke
				(width 0.1)
				(type default)
			)
			(layer "F.Fab")
		)
		(pad "1" smd rect
			(at -0.2667 0 270)
			(size 0.3048 0.381)
			(layers "F.Cu" "F.Mask" "F.Paste")
			(net "P5E_CPU0_PE2_TX_C_DP<14>")
		)
		(pad "2" smd rect
			(at 0.2667 0 270)
			(size 0.3048 0.381)
			(layers "F.Cu" "F.Mask" "F.Paste")
			(net "P5E_CPU0_PE2_TX_DP<14>")
		)
	)
	(footprint ""
		(layer "F.Cu")
		(at 197.104 -92.801948 90)
		(property "Reference" "R4610"
			(at 0 0 90)
			(layer "F.SilkS")
			(hide yes)
			(effects
				(font
					(size 1.27 1.27)
				)
			)
		)
		(property "Value" ""
			(at 0 0 90)
			(layer "F.Fab")
			(effects
				(font
					(size 1.27 1.27)
				)
			)
		)
		(duplicate_pad_numbers_are_jumpers no)
		(fp_line
			(start 0.7874 -0.4064)
			(end 0.7874 0.4064)
			(stroke
				(width 0.1524)
				(type default)
			)
			(layer "F.SilkS")
		)
		(fp_line
			(start -0.7874 -0.4064)
			(end 0.7874 -0.4064)
			(stroke
				(width 0.1524)
				(type default)
			)
			(layer "F.SilkS")
		)
		(fp_line
			(start 0.7874 0.4064)
			(end -0.7874 0.4064)
			(stroke
				(width 0.1524)
				(type default)
			)
			(layer "F.SilkS")
		)
		(fp_line
			(start -0.7874 0.4064)
			(end -0.7874 -0.4064)
			(stroke
				(width 0.1524)
				(type default)
			)
			(layer "F.SilkS")
		)
		(fp_line
			(start -0.12065 -0.305054)
			(end -0.12065 -0.2794)
			(stroke
				(width 0.1)
				(type default)
			)
			(layer "F.Fab")
		)
		(fp_line
			(start -0.67945 -0.305054)
			(end -0.12065 -0.305054)
			(stroke
				(width 0.1)
				(type default)
			)
			(layer "F.Fab")
		)
		(fp_line
			(start 0.67945 -0.3048)
			(end 0.67945 0.3048)
			(stroke
				(width 0.1)
				(type default)
			)
			(layer "F.Fab")
		)
		(fp_line
			(start 0.12065 -0.3048)
			(end 0.67945 -0.3048)
			(stroke
				(width 0.1)
				(type default)
			)
			(layer "F.Fab")
		)
		(fp_line
			(start 0.12065 -0.2794)
			(end 0.12065 -0.3048)
			(stroke
				(width 0.1)
				(type default)
			)
			(layer "F.Fab")
		)
		(fp_line
			(start -0.12065 -0.2794)
			(end 0.12065 -0.2794)
			(stroke
				(width 0.1)
				(type default)
			)
			(layer "F.Fab")
		)
		(fp_line
			(start 0.120396 0.2794)
			(end -0.12065 0.2794)
			(stroke
				(width 0.1)
				(type default)
			)
			(layer "F.Fab")
		)
		(fp_line
			(start -0.12065 0.2794)
			(end -0.12065 0.3048)
			(stroke
				(width 0.1)
				(type default)
			)
			(layer "F.Fab")
		)
		(fp_line
			(start 0.67945 0.3048)
			(end 0.120396 0.3048)
			(stroke
				(width 0.1)
				(type default)
			)
			(layer "F.Fab")
		)
		(fp_line
			(start 0.120396 0.3048)
			(end 0.120396 0.2794)
			(stroke
				(width 0.1)
				(type default)
			)
			(layer "F.Fab")
		)
		(fp_line
			(start -0.12065 0.3048)
			(end -0.67945 0.3048)
			(stroke
				(width 0.1)
				(type default)
			)
			(layer "F.Fab")
		)
		(fp_line
			(start -0.67945 0.3048)
			(end -0.67945 -0.305054)
			(stroke
				(width 0.1)
				(type default)
			)
			(layer "F.Fab")
		)
		(pad "1" smd circle
			(at -0.40005 0 90)
			(size 0 0)
			(layers "F.Cu" "F.Mask" "F.Paste")
			(net "CLK_GEN2_GPU_FPGA_OE_R_N")
		)
		(pad "2" smd circle
			(at 0.40005 0 90)
			(size 0 0)
			(layers "F.Cu" "F.Mask" "F.Paste")
			(net "CLK_GEN2_GPU_FPGA_OE_N")
		)
	)
)
